# S9S_MB_2U (Grand Teton) — schematic netlist excerpt (pin names and nets, part order shuffled) for the footprints in the layout excerpt that follows; sources: Cadence DE-HDL packaged netlist, KiCad conversion of 03242023_DA0F0TMBIJ0_F0T_Motherboard_J_brd_V01_OCP.brd

C750  Q_CAP_DIFFBUS  DIFF BUS_0.22UF 6.3V 20% X6S  pkg C0201  page 176 : \1\ = P5E_CPU1_PE2_TX_C_DN<11> ; \2\ = P5E_CPU1_PE2_TX_DN<11>
PR3964  Q_RES  7.15K 1% CHIP  pkg 0402LF  page 192 : A = P3V3_E1S_UV_0 ; B = P3V3_E1S_OV_0
R2792  Q_RES  0 5% CHIP  pkg 0402LF  page 215 : A = FM_PDB_BUF_EN ; B = FM_PDB_BUF_EN_R

(kicad_pcb
	(version 20260206)
	(generator "pcbnew")
	(generator_version "10.0")
	(general
		(thickness 1.6)
		(legacy_teardrops no)
	)
	(paper "A4")
	(title_block
		(title "03242023_DA0F0TMBIJ0_F0T_Motherboard_J_brd_V01_OCP.brd")
		(comment 1 "Grand Teton / footprints 3064-3066 of 6105")
	)
	(layers
		(0 "F.Cu" signal "TOP")
		(4 "In1.Cu" signal "GND")
		(6 "In2.Cu" signal "IN1")
		(8 "In3.Cu" signal "GND1")
		(10 "In4.Cu" signal "IN2")
		(12 "In5.Cu" signal "GND2")
		(14 "In6.Cu" signal "IN3")
		(16 "In7.Cu" signal "GND3")
		(18 "In8.Cu" signal "VCC")
		(20 "In9.Cu" signal "VCC1")
		(22 "In10.Cu" signal "GND4")
		(24 "In11.Cu" signal "IN4")
		(26 "In12.Cu" signal "GND5")
		(28 "In13.Cu" signal "IN5")
		(30 "In14.Cu" signal "GND6")
		(32 "In15.Cu" signal "IN6")
		(34 "In16.Cu" signal "GND7")
		(2 "B.Cu" signal "BOTTOM")
		(9 "F.Adhes" user "F.Adhesive")
		(11 "B.Adhes" user "B.Adhesive")
		(13 "F.Paste" user "Package Geometry/Pastemask Top")
		(15 "B.Paste" user "Package Geometry/Pastemask Bottom")
		(5 "F.SilkS" user "Ref Des/Silkscreen Top")
		(7 "B.SilkS" user "Ref Des/Silkscreen Bottom")
		(1 "F.Mask" user "Board Geometry/Soldermask Top")
		(3 "B.Mask" user "Board Geometry/Soldermask Bottom")
		(17 "Dwgs.User" user "User.Drawings")
		(19 "Cmts.User" user "User.Comments")
		(21 "Eco1.User" user "User.Eco1")
		(23 "Eco2.User" user "User.Eco2")
		(25 "Edge.Cuts" user "Board Geometry/Outline")
		(27 "Margin" user)
		(31 "F.CrtYd" user "Package Geometry/Place Bound Top")
		(29 "B.CrtYd" user "Package Geometry/Place Bound Bottom")
		(35 "F.Fab" user "Ref Des/Assembly Top")
		(33 "B.Fab" user "Ref Des/Assembly Bottom")
	)
	(footprint ""
		(layer "F.Cu")
		(at 193.38036 -122.900948)
		(property "Reference" "R2792"
			(at 0 0 0)
			(layer "F.SilkS")
			(hide yes)
			(effects
				(font
					(size 1.27 1.27)
				)
			)
		)
		(property "Value" ""
			(at 0 0 0)
			(layer "F.Fab")
			(effects
				(font
					(size 1.27 1.27)
				)
			)
		)
		(duplicate_pad_numbers_are_jumpers no)
		(fp_line
			(start -0.7874 -0.4064)
			(end 0.7874 -0.4064)
			(stroke
				(width 0.1524)
				(type default)
			)
			(layer "F.SilkS")
		)
		(fp_line
			(start -0.7874 0.4064)
			(end -0.7874 -0.4064)
			(stroke
				(width 0.1524)
				(type default)
			)
			(layer "F.SilkS")
		)
		(fp_line
			(start 0.7874 -0.4064)
			(end 0.7874 0.4064)
			(stroke
				(width 0.1524)
				(type default)
			)
			(layer "F.SilkS")
		)
		(fp_line
			(start 0.7874 0.4064)
			(end -0.7874 0.4064)
			(stroke
				(width 0.1524)
				(type default)
			)
			(layer "F.SilkS")
		)
		(fp_line
			(start -0.67945 -0.305054)
			(end -0.12065 -0.305054)
			(stroke
				(width 0.1)
				(type default)
			)
			(layer "F.Fab")
		)
		(fp_line
			(start -0.67945 0.3048)
			(end -0.67945 -0.305054)
			(stroke
				(width 0.1)
				(type default)
			)
			(layer "F.Fab")
		)
		(fp_line
			(start -0.12065 -0.305054)
			(end -0.12065 -0.2794)
			(stroke
				(width 0.1)
				(type default)
			)
			(layer "F.Fab")
		)
		(fp_line
			(start -0.12065 -0.2794)
			(end 0.12065 -0.2794)
			(stroke
				(width 0.1)
				(type default)
			)
			(layer "F.Fab")
		)
		(fp_line
			(start -0.12065 0.2794)
			(end -0.12065 0.3048)
			(stroke
				(width 0.1)
				(type default)
			)
			(layer "F.Fab")
		)
		(fp_line
			(start -0.12065 0.3048)
			(end -0.67945 0.3048)
			(stroke
				(width 0.1)
				(type default)
			)
			(layer "F.Fab")
		)
		(fp_line
			(start 0.120396 0.2794)
			(end -0.12065 0.2794)
			(stroke
				(width 0.1)
				(type default)
			)
			(layer "F.Fab")
		)
		(fp_line
			(start 0.120396 0.3048)
			(end 0.120396 0.2794)
			(stroke
				(width 0.1)
				(type default)
			)
			(layer "F.Fab")
		)
		(fp_line
			(start 0.12065 -0.3048)
			(end 0.67945 -0.3048)
			(stroke
				(width 0.1)
				(type default)
			)
			(layer "F.Fab")
		)
		(fp_line
			(start 0.12065 -0.2794)
			(end 0.12065 -0.3048)
			(stroke
				(width 0.1)
				(type default)
			)
			(layer "F.Fab")
		)
		(fp_line
			(start 0.67945 -0.3048)
			(end 0.67945 0.3048)
			(stroke
				(width 0.1)
				(type default)
			)
			(layer "F.Fab")
		)
		(fp_line
			(start 0.67945 0.3048)
			(end 0.120396 0.3048)
			(stroke
				(width 0.1)
				(type default)
			)
			(layer "F.Fab")
		)
		(pad "1" smd circle
			(at -0.40005 0)
			(size 0 0)
			(layers "F.Cu" "F.Mask" "F.Paste")
			(net "FM_PDB_BUF_EN")
		)
		(pad "2" smd circle
			(at 0.40005 0)
			(size 0 0)
			(layers "F.Cu" "F.Mask" "F.Paste")
			(net "FM_PDB_BUF_EN_R")
		)
	)
	(footprint ""
		(layer "F.Cu")
		(at 133.296914 -402.371052 -90)
		(property "Reference" "C750"
			(at 0 0 270)
			(layer "F.SilkS")
			(hide yes)
			(effects
				(font
					(size 1.27 1.27)
				)
			)
		)
		(property "Value" ""
			(at 0 0 270)
			(layer "F.Fab")
			(effects
				(font
					(size 1.27 1.27)
				)
			)
		)
		(duplicate_pad_numbers_are_jumpers no)
		(fp_line
			(start -0.299974 0.150114)
			(end -0.299974 -0.150114)
			(stroke
				(width 0.1)
				(type default)
			)
			(layer "F.Fab")
		)
		(fp_line
			(start 0.299974 0.150114)
			(end -0.299974 0.150114)
			(stroke
				(width 0.1)
				(type default)
			)
			(layer "F.Fab")
		)
		(fp_line
			(start -0.299974 -0.150114)
			(end 0.299974 -0.150114)
			(stroke
				(width 0.1)
				(type default)
			)
			(layer "F.Fab")
		)
		(fp_line
			(start 0.299974 -0.150114)
			(end 0.299974 0.150114)
			(stroke
				(width 0.1)
				(type default)
			)
			(layer "F.Fab")
		)
		(pad "1" smd rect
			(at -0.2667 0 270)
			(size 0.3048 0.381)
			(layers "F.Cu" "F.Mask" "F.Paste")
			(net "P5E_CPU1_PE2_TX_C_DN<11>")
		)
		(pad "2" smd rect
			(at 0.2667 0 270)
			(size 0.3048 0.381)
			(layers "F.Cu" "F.Mask" "F.Paste")
			(net "P5E_CPU1_PE2_TX_DN<11>")
		)
	)
	(footprint ""
		(layer "F.Cu")
		(at 219.276676 -67.954144 -90)
		(property "Reference" "PR3964"
			(at 0 0 270)
			(layer "F.SilkS")
			(hide yes)
			(effects
				(font
					(size 1.27 1.27)
				)
			)
		)
		(property "Value" ""
			(at 0 0 270)
			(layer "F.Fab")
			(effects
				(font
					(size 1.27 1.27)
				)
			)
		)
		(duplicate_pad_numbers_are_jumpers no)
		(fp_line
			(start -0.7874 0.4064)
			(end -0.7874 -0.4064)
			(stroke
				(width 0.1524)
				(type default)
			)
			(layer "F.SilkS")
		)
		(fp_line
			(start 0.7874 0.4064)
			(end -0.7874 0.4064)
			(stroke
				(width 0.1524)
				(type default)
			)
			(layer "F.SilkS")
		)
		(fp_line
			(start -0.7874 -0.4064)
			(end 0.7874 -0.4064)
			(stroke
				(width 0.1524)
				(type default)
			)
			(layer "F.SilkS")
		)
		(fp_line
			(start 0.7874 -0.4064)
			(end 0.7874 0.4064)
			(stroke
				(width 0.1524)
				(type default)
			)
			(layer "F.SilkS")
		)
		(fp_line
			(start -0.67945 0.3048)
			(end -0.67945 -0.305054)
			(stroke
				(width 0.1)
				(type default)
			)
			(layer "F.Fab")
		)
		(fp_line
			(start -0.12065 0.3048)
			(end -0.67945 0.3048)
			(stroke
				(width 0.1)
				(type default)
			)
			(layer "F.Fab")
		)
		(fp_line
			(start 0.120396 0.3048)
			(end 0.120396 0.2794)
			(stroke
				(width 0.1)
				(type default)
			)
			(layer "F.Fab")
		)
		(fp_line
			(start 0.67945 0.3048)
			(end 0.120396 0.3048)
			(stroke
				(width 0.1)
				(type default)
			)
			(layer "F.Fab")
		)
		(fp_line
			(start -0.12065 0.2794)
			(end -0.12065 0.3048)
			(stroke
				(width 0.1)
				(type default)
			)
			(layer "F.Fab")
		)
		(fp_line
			(start 0.120396 0.2794)
			(end -0.12065 0.2794)
			(stroke
				(width 0.1)
				(type default)
			)
			(layer "F.Fab")
		)
		(fp_line
			(start -0.12065 -0.2794)
			(end 0.12065 -0.2794)
			(stroke
				(width 0.1)
				(type default)
			)
			(layer "F.Fab")
		)
		(fp_line
			(start 0.12065 -0.2794)
			(end 0.12065 -0.3048)
			(stroke
				(width 0.1)
				(type default)
			)
			(layer "F.Fab")
		)
		(fp_line
			(start 0.12065 -0.3048)
			(end 0.67945 -0.3048)
			(stroke
				(width 0.1)
				(type default)
			)
			(layer "F.Fab")
		)
		(fp_line
			(start 0.67945 -0.3048)
			(end 0.67945 0.3048)
			(stroke
				(width 0.1)
				(type default)
			)
			(layer "F.Fab")
		)
		(fp_line
			(start -0.67945 -0.305054)
			(end -0.12065 -0.305054)
			(stroke
				(width 0.1)
				(type default)
			)
			(layer "F.Fab")
		)
		(fp_line
			(start -0.12065 -0.305054)
			(end -0.12065 -0.2794)
			(stroke
				(width 0.1)
				(type default)
			)
			(layer "F.Fab")
		)
		(pad "1" smd circle
			(at -0.40005 0 270)
			(size 0 0)
			(layers "F.Cu" "F.Mask" "F.Paste")
			(net "P3V3_E1S_UV_0")
		)
		(pad "2" smd circle
			(at 0.40005 0 270)
			(size 0 0)
			(layers "F.Cu" "F.Mask" "F.Paste")
			(net "P3V3_E1S_OV_0")
		)
	)
)
